(kicad_pcb
	(version 20260206)
	(generator "pcbnew")
	(generator_version "10.0")
	(general
		(thickness 1.21888)
		(legacy_teardrops no)
	)
	(paper "A4")
	(title_block
		(title "timecard-v9 — TimeCard-DC-V9_EXP.PcbDoc")
		(comment 1 "Time Appliance Project (Time Card) / footprints 149-154 of 402")
	)
	(layers
		(0 "F.Cu" signal "TOP")
		(4 "In1.Cu" signal "SGND")
		(6 "In2.Cu" signal "IN1")
		(8 "In3.Cu" signal "IN2")
		(10 "In4.Cu" signal "SGND1")
		(2 "B.Cu" signal "BOTTOM")
		(9 "F.Adhes" user "F.Adhesive")
		(11 "B.Adhes" user "B.Adhesive")
		(13 "F.Paste" user "Top Paste")
		(15 "B.Paste" user "Bottom Paste")
		(5 "F.SilkS" user "Top Overlay")
		(7 "B.SilkS" user "Bottom Overlay")
		(1 "F.Mask" user "Top Solder")
		(3 "B.Mask" user "Bottom Solder")
		(17 "Dwgs.User" user "User.Drawings")
		(19 "Cmts.User" user "User.Comments")
		(21 "Eco1.User" user "User.Eco1")
		(23 "Eco2.User" user "User.Eco2")
		(25 "Edge.Cuts" user)
		(27 "Margin" user)
		(31 "F.CrtYd" user "Top Courtyard")
		(29 "B.CrtYd" user "Bottom Courtyard")
		(35 "F.Fab" user "Top Component Center")
		(33 "B.Fab" user "Bottom Component Center")
	)
	(footprint "Vault:RESC1005X40X25LL05T10"
		(layer "F.Cu")
		(at 141.0216 103.9162 180)
		(property "Reference" "R104"
			(at 1.9714 0.173079 0)
			(unlocked yes)
			(layer "F.SilkS")
			(effects
				(font
					(size 0.762 0.762)
					(thickness 0.2286)
				)
			)
		)
		(property "Value" "DNI_49.9_1%_0402"
			(at -2.579871 11.74372 90)
			(unlocked yes)
			(layer "F.SilkS")
			(hide yes)
			(effects
				(font
					(size 0.762 0.762)
					(thickness 0.2286)
				)
			)
		)
		(sheetname "09-USBUart_PPSMUX_UARTMUX")
		(sheetfile "09-USBUart_PPSMUX_UARTMUX.kicad_sch")
		(duplicate_pad_numbers_are_jumpers no)
		(pad "1" smd rect
			(at -0.375 0 270)
			(size 0.45 0.5)
			(layers "F.Cu" "F.Mask" "F.Paste")
			(net "FPGA_MAC_PPS_OUT-")
		)
		(pad "2" smd rect
			(at 0.375 0 270)
			(size 0.45 0.5)
			(layers "F.Cu" "F.Mask" "F.Paste")
			(net "MAC_PPS_OUT")
		)
	)
	(footprint "Vault:AMPH-901-143-6RFX_V"
		(layer "F.Cu")
		(at 69.9716 122.0782 180)
		(property "Reference" "AN3"
			(at 0.85 3.868655 0)
			(unlocked yes)
			(layer "F.SilkS")
			(effects
				(font
					(size 0.762 0.762)
					(thickness 0.2286)
				)
				(justify left bottom)
			)
		)
		(property "Value" "RF2-49B-T-00-50-G-HDW"
			(at 4.6101 -1.960245 0)
			(unlocked yes)
			(layer "F.SilkS")
			(hide yes)
			(effects
				(font
					(size 0.762 0.762)
					(thickness 0.2286)
				)
				(justify left bottom)
			)
		)
		(sheetname "01-USER_IO")
		(sheetfile "01-USER_IO.kicad_sch")
		(duplicate_pad_numbers_are_jumpers no)
		(fp_line
			(start 3.5 -1.38)
			(end 3.5 1.38)
			(stroke
				(width 0.2)
				(type solid)
			)
			(layer "F.SilkS")
		)
		(fp_line
			(start 1.38 3.5)
			(end -1.38 3.5)
			(stroke
				(width 0.2)
				(type solid)
			)
			(layer "F.SilkS")
		)
		(fp_line
			(start 1.38 -3.5)
			(end -1.38 -3.5)
			(stroke
				(width 0.2)
				(type solid)
			)
			(layer "F.SilkS")
		)
		(fp_line
			(start -3.5 -1.38)
			(end -3.5 1.38)
			(stroke
				(width 0.2)
				(type solid)
			)
			(layer "F.SilkS")
		)
		(pad "1" thru_hole rect
			(at 0 0 180)
			(size 2 2)
			(drill 1.5)
			(layers "*.Cu" "*.Mask")
			(remove_unused_layers no)
			(net "NetAN3_1")
		)
		(pad "2" thru_hole circle
			(at -2.54 -2.54 180)
			(size 2.2 2.2)
			(drill 1.7)
			(layers "*.Cu" "*.Mask")
			(remove_unused_layers no)
			(net "GND")
			(thermal_bridge_angle 90)
		)
		(pad "3" thru_hole circle
			(at -2.54 2.54 180)
			(size 2.2 2.2)
			(drill 1.7)
			(layers "*.Cu" "*.Mask")
			(remove_unused_layers no)
			(net "GND")
			(thermal_bridge_angle 90)
		)
		(pad "4" thru_hole circle
			(at 2.54 2.54 180)
			(size 2.2 2.2)
			(drill 1.7)
			(layers "*.Cu" "*.Mask")
			(remove_unused_layers no)
			(net "GND")
			(thermal_bridge_angle 90)
		)
		(pad "5" thru_hole circle
			(at 2.54 -2.54 180)
			(size 2.2 2.2)
			(drill 1.7)
			(layers "*.Cu" "*.Mask")
			(remove_unused_layers no)
			(net "GND")
			(thermal_bridge_angle 90)
		)
	)
	(footprint "Vault:RESC1005X40X25LL05T10"
		(layer "F.Cu")
		(at 196.9216 134.9162)
		(property "Reference" "R145"
			(at 1.5032 0.826921 0)
			(unlocked yes)
			(layer "F.SilkS")
			(effects
				(font
					(size 0.762 0.762)
					(thickness 0.2032)
				)
			)
		)
		(property "Value" "49.9_1%_0402"
			(at -2.579881 8.798275 270)
			(unlocked yes)
			(layer "F.SilkS")
			(hide yes)
			(effects
				(font
					(size 0.762 0.762)
					(thickness 0.2032)
				)
			)
		)
		(sheetname "11-M2_RCB_MUX")
		(sheetfile "11-M2_RCB_MUX.kicad_sch")
		(duplicate_pad_numbers_are_jumpers no)
		(pad "1" smd rect
			(at -0.375 0 90)
			(size 0.45 0.5)
			(layers "F.Cu" "F.Mask" "F.Paste")
			(net "NetR145_1")
		)
		(pad "2" smd rect
			(at 0.375 0 90)
			(size 0.45 0.5)
			(layers "F.Cu" "F.Mask" "F.Paste")
			(net "GPS2_TP1")
		)
	)
	(footprint "Vault:RESC1005X40X25NL05T05"
		(layer "F.Cu")
		(at 110.5216 51.0162 90)
		(property "Reference" "R162"
			(at -0.5968 8.426931 90)
			(unlocked yes)
			(layer "F.SilkS")
			(effects
				(font
					(size 0.762 0.762)
					(thickness 0.2032)
				)
			)
		)
		(property "Value" "DNI_27_1%_0402"
			(at -2.732271 10.270965 0)
			(unlocked yes)
			(layer "F.SilkS")
			(hide yes)
			(effects
				(font
					(size 0.762 0.762)
					(thickness 0.2032)
				)
			)
		)
		(sheetname "11-M2_RCB_MUX")
		(sheetfile "11-M2_RCB_MUX.kicad_sch")
		(duplicate_pad_numbers_are_jumpers no)
		(pad "1" smd rect
			(at -0.45 0 180)
			(size 0.55 0.55)
			(layers "F.Cu" "F.Mask" "F.Paste")
			(net "M2_GPS1_TX")
		)
		(pad "2" smd rect
			(at 0.45 0 180)
			(size 0.55 0.55)
			(layers "F.Cu" "F.Mask" "F.Paste")
			(net "GPS1_TX")
		)
	)
	(footprint ""
		(layer "F.Cu")
		(at 180.0216 65.0162)
		(property "Reference" ""
			(at 0 0 0)
			(layer "F.SilkS")
			(effects
				(font
					(size 1.27 1.27)
				)
			)
		)
		(property "Value" ""
			(at 0 0 0)
			(layer "F.Fab")
			(effects
				(font
					(size 1.27 1.27)
				)
			)
		)
		(duplicate_pad_numbers_are_jumpers no)
		(pad "2" thru_hole circle
			(at 0 0)
			(size 6.5 6.5)
			(drill 4.2)
			(layers "*.Cu" "*.Mask")
			(remove_unused_layers no)
			(net "GND")
			(thermal_bridge_angle 90)
		)
	)
	(footprint "Vault:RESC1005X40X25LL05T10"
		(layer "F.Cu")
		(at 190.4216 133.9162 -90)
		(property "Reference" "R146"
			(at 2.5032 0.226931 270)
			(unlocked yes)
			(layer "F.SilkS")
			(effects
				(font
					(size 0.762 0.762)
					(thickness 0.2032)
				)
			)
		)
		(property "Value" "49.9_1%_0402"
			(at -2.579871 8.798265 180)
			(unlocked yes)
			(layer "F.SilkS")
			(hide yes)
			(effects
				(font
					(size 0.762 0.762)
					(thickness 0.2032)
				)
			)
		)
		(sheetname "11-M2_RCB_MUX")
		(sheetfile "11-M2_RCB_MUX.kicad_sch")
		(duplicate_pad_numbers_are_jumpers no)
		(pad "1" smd rect
			(at -0.375 0)
			(size 0.45 0.5)
			(layers "F.Cu" "F.Mask" "F.Paste")
			(net "NetR146_1")
		)
		(pad "2" smd rect
			(at 0.375 0)
			(size 0.45 0.5)
			(layers "F.Cu" "F.Mask" "F.Paste")
			(net "GPS2_RX")
		)
	)
)
